(kicad_pcb
	(version 20241229)
	(generator "pcbnew")
	(generator_version "9.0")
	(general
		(thickness 1.61)
		(legacy_teardrops no)
	)
	(paper "A3")
	(title_block
		(title "SO-DIMM DDR5 Tester")
		(date "2025-11-26")
		(rev "1.3.0")
		(comment 9 "footprint 59 of 627 (U4), pads 1-72 of 676")
	)
	(layers
		(0 "F.Cu" signal)
		(4 "In1.Cu" power)
		(6 "In2.Cu" mixed)
		(8 "In3.Cu" power)
		(10 "In4.Cu" mixed)
		(12 "In5.Cu" power)
		(14 "In6.Cu" mixed)
		(16 "In7.Cu" power)
		(18 "In8.Cu" power)
		(20 "In9.Cu" mixed)
		(22 "In10.Cu" power)
		(2 "B.Cu" signal)
		(9 "F.Adhes" user "F.Adhesive")
		(11 "B.Adhes" user "B.Adhesive")
		(13 "F.Paste" user)
		(15 "B.Paste" user)
		(5 "F.SilkS" user "F.Silkscreen")
		(7 "B.SilkS" user "B.Silkscreen")
		(1 "F.Mask" user)
		(3 "B.Mask" user)
		(17 "Dwgs.User" user "User.Drawings")
		(19 "Cmts.User" user "User.Comments")
		(21 "Eco1.User" user "User.Eco1")
		(23 "Eco2.User" user "User.Eco2")
		(25 "Edge.Cuts" user)
		(27 "Margin" user)
		(31 "F.CrtYd" user "F.Courtyard")
		(29 "B.CrtYd" user "B.Courtyard")
		(35 "F.Fab" user)
		(33 "B.Fab" user)
	)
	(footprint "antmicro-footprints:BGA-676_27x27mm_Layout26x26_P1x1mm_FFG676"
		(layer "F.Cu")
		(at 138.875501 174.801 180)
		(descr "FPGA XC7K160TFBG676")
		(tags "FPGA XC7K160TFBG676")
		(property "Reference" "U4"
			(at -12.224499 14.051 180)
			(layer "F.SilkS")
			(effects
				(font
					(size 0.7 0.7)
					(thickness 0.15)
				)
				(justify left bottom)
			)
		)
		(property "Value" "XC7K160T-FFG676"
			(at 0 15.5 180)
			(layer "F.Fab")
			(effects
				(font
					(size 0.7 0.7)
					(thickness 0.15)
				)
				(justify left bottom)
			)
		)
		(property "Datasheet" "https://docs.xilinx.com/v/u/en-US/ds180_7Series_Overview"
			(at 0 0 180)
			(layer "F.Fab")
			(hide yes)
			(effects
				(font
					(size 1.27 1.27)
					(thickness 0.15)
				)
			)
		)
		(property "Author" "Antmicro"
			(at 277.751002 349.602 0)
			(layer "F.Fab")
			(hide yes)
			(effects
				(font
					(size 1 1)
					(thickness 0.15)
				)
			)
		)
		(property "License" "Apache-2.0"
			(at 277.751002 349.602 0)
			(layer "F.Fab")
			(hide yes)
			(effects
				(font
					(size 1 1)
					(thickness 0.15)
				)
			)
		)
		(property "MPN" "XC7K160T-FFG676"
			(at 277.751002 349.602 0)
			(layer "F.Fab")
			(hide yes)
			(effects
				(font
					(size 1 1)
					(thickness 0.15)
				)
			)
		)
		(property "Manufacturer" "AMD-Xilinx"
			(at 277.751002 349.602 0)
			(layer "F.Fab")
			(hide yes)
			(effects
				(font
					(size 1 1)
					(thickness 0.15)
				)
			)
		)
		(sheetname "/FPGA Config/")
		(sheetfile "fpga-config.kicad_sch")
		(attr smd)
		(pad "A1" smd circle
			(at -12.5 -12.5 180)
			(size 0.5 0.5)
			(layers "F.Cu" "F.Mask" "F.Paste")
			(net 1 "GND")
			(pinfunction "GND")
			(pintype "power_in")
		)
		(pad "A2" smd circle
			(at -11.5 -12.5 180)
			(size 0.5 0.5)
			(layers "F.Cu" "F.Mask" "F.Paste")
			(net 1 "GND")
			(pinfunction "GND")
			(pintype "passive")
		)
		(pad "A3" smd circle
			(at -10.5 -12.5 180)
			(size 0.5 0.5)
			(layers "F.Cu" "F.Mask" "F.Paste")
			(net 29 "/FPGA MGT Interface/GTX_TX3_N")
			(pinfunction "MGTXTXN3_116")
			(pintype "bidirectional")
			(die_length 14.476)
		)
		(pad "A4" smd circle
			(at -9.5 -12.5 180)
			(size 0.5 0.5)
			(layers "F.Cu" "F.Mask" "F.Paste")
			(net 23 "/FPGA MGT Interface/GTX_TX3_P")
			(pinfunction "MGTXTXP3_116")
			(pintype "bidirectional")
			(die_length 14.628)
		)
		(pad "A5" smd circle
			(at -8.5 -12.5 180)
			(size 0.5 0.5)
			(layers "F.Cu" "F.Mask" "F.Paste")
			(net 1 "GND")
			(pinfunction "GND")
			(pintype "passive")
		)
		(pad "A6" smd circle
			(at -7.5 -12.5 180)
			(size 0.5 0.5)
			(layers "F.Cu" "F.Mask" "F.Paste")
			(net 1 "GND")
			(pinfunction "GND")
			(pintype "passive")
		)
		(pad "A7" smd circle
			(at -6.5 -12.5 180)
			(size 0.5 0.5)
			(layers "F.Cu" "F.Mask" "F.Paste")
			(net 1 "GND")
			(pinfunction "GND")
			(pintype "passive")
		)
		(pad "A8" smd circle
			(at -5.5 -12.5 180)
			(size 0.5 0.5)
			(layers "F.Cu" "F.Mask" "F.Paste")
			(net 135 "PCIE.PWRGD")
			(pinfunction "IO_L9N_T1_DQS_16")
			(pintype "bidirectional")
			(die_length 19.908)
		)
		(pad "A9" smd circle
			(at -4.5 -12.5 180)
			(size 0.5 0.5)
			(layers "F.Cu" "F.Mask" "F.Paste")
			(net 394 "unconnected-(U4E-IO_L9P_T1_DQS_16-PadA9)")
			(pinfunction "IO_L9P_T1_DQS_16")
			(pintype "bidirectional+no_connect")
			(die_length 19.519)
		)
		(pad "A10" smd circle
			(at -3.5 -12.5 180)
			(size 0.5 0.5)
			(layers "F.Cu" "F.Mask" "F.Paste")
			(net 661 "/FPGA bank 16/HDMI.D2_N")
			(pinfunction "IO_L22N_T3_16")
			(pintype "bidirectional")
			(die_length 20.762)
		)
		(pad "A11" smd circle
			(at -2.5 -12.5 180)
			(size 0.5 0.5)
			(layers "F.Cu" "F.Mask" "F.Paste")
			(net 200 "+3V3")
			(pinfunction "VCCO_16")
			(pintype "power_in")
		)
		(pad "A12" smd circle
			(at -1.5 -12.5 180)
			(size 0.5 0.5)
			(layers "F.Cu" "F.Mask" "F.Paste")
			(net 663 "/FPGA bank 16/HDMI.D1_N")
			(pinfunction "IO_L24N_T3_16")
			(pintype "bidirectional")
			(die_length 22.422)
		)
		(pad "A13" smd circle
			(at -0.5 -12.5 180)
			(size 0.5 0.5)
			(layers "F.Cu" "F.Mask" "F.Paste")
			(net 662 "/FPGA bank 16/HDMI.D1_P")
			(pinfunction "IO_L24P_T3_16")
			(pintype "bidirectional")
			(die_length 22.76)
		)
		(pad "A14" smd circle
			(at 0.499 -12.5 180)
			(size 0.5 0.5)
			(layers "F.Cu" "F.Mask" "F.Paste")
			(net 665 "/FPGA bank 16/HDMI.D0_N")
			(pinfunction "IO_L21N_T3_DQS_16")
			(pintype "bidirectional")
			(die_length 18.115)
		)
		(pad "A15" smd circle
			(at 1.499 -12.5 180)
			(size 0.5 0.5)
			(layers "F.Cu" "F.Mask" "F.Paste")
			(net 667 "/FPGA bank 16/HDMI.CLK_N")
			(pinfunction "IO_L23N_T3_16")
			(pintype "bidirectional")
			(die_length 18.152)
		)
		(pad "A16" smd circle
			(at 2.499 -12.5 180)
			(size 0.5 0.5)
			(layers "F.Cu" "F.Mask" "F.Paste")
			(net 1 "GND")
			(pinfunction "GND")
			(pintype "passive")
		)
		(pad "A17" smd circle
			(at 3.499 -12.5 180)
			(size 0.5 0.5)
			(layers "F.Cu" "F.Mask" "F.Paste")
			(net 395 "unconnected-(U4D-IO_L3N_T0_DQS_AD1N_15-PadA17)")
			(pinfunction "IO_L3N_T0_DQS_AD1N_15")
			(pintype "bidirectional+no_connect")
			(die_length 18.146)
		)
		(pad "A18" smd circle
			(at 4.499 -12.5 180)
			(size 0.5 0.5)
			(layers "F.Cu" "F.Mask" "F.Paste")
			(net 396 "unconnected-(U4D-IO_L2P_T0_AD8P_15-PadA18)")
			(pinfunction "IO_L2P_T0_AD8P_15")
			(pintype "bidirectional+no_connect")
			(die_length 20.209)
		)
		(pad "A19" smd circle
			(at 5.499 -12.5 180)
			(size 0.5 0.5)
			(layers "F.Cu" "F.Mask" "F.Paste")
			(net 397 "unconnected-(U4D-IO_L2N_T0_AD8N_15-PadA19)")
			(pinfunction "IO_L2N_T0_AD8N_15")
			(pintype "bidirectional+no_connect")
			(die_length 19.837)
		)
		(pad "A20" smd circle
			(at 6.499 -12.5 180)
			(size 0.5 0.5)
			(layers "F.Cu" "F.Mask" "F.Paste")
			(net 234 "HOT_SWAP_YELLOW")
			(pinfunction "IO_L8N_T1_D12_14")
			(pintype "bidirectional")
			(die_length 22.195)
		)
		(pad "A21" smd circle
			(at 7.499 -12.5 180)
			(size 0.5 0.5)
			(layers "F.Cu" "F.Mask" "F.Paste")
			(net 200 "+3V3")
			(pinfunction "VCCO_14")
			(pintype "power_in")
		)
		(pad "A22" smd circle
			(at 8.499 -12.5 180)
			(size 0.5 0.5)
			(layers "F.Cu" "F.Mask" "F.Paste")
			(net 629 "/FPGA Config/FLASH.IO3")
			(pinfunction "IO_L2N_T0_D03_14")
			(pintype "bidirectional")
			(die_length 21.482)
		)
		(pad "A23" smd circle
			(at 9.499 -12.5 180)
			(size 0.5 0.5)
			(layers "F.Cu" "F.Mask" "F.Paste")
			(net 645 "/Debug FTDI/UART1.TX")
			(pinfunction "IO_L4P_T0_D04_14")
			(pintype "bidirectional")
			(die_length 21.833)
		)
		(pad "A24" smd circle
			(at 10.499 -12.5 180)
			(size 0.5 0.5)
			(layers "F.Cu" "F.Mask" "F.Paste")
			(net 643 "/Debug FTDI/UART1.RX")
			(pinfunction "IO_L4N_T0_D05_14")
			(pintype "bidirectional")
			(die_length 22.897)
		)
		(pad "A25" smd circle
			(at 11.499 -12.5 180)
			(size 0.5 0.5)
			(layers "F.Cu" "F.Mask" "F.Paste")
			(net 627 "/FPGA Config/FLASH.IO1")
			(pinfunction "IO_L1N_T0_D01_DIN_14")
			(pintype "bidirectional")
			(die_length 23.845)
		)
		(pad "A26" smd circle
			(at 12.499 -12.5 180)
			(size 0.5 0.5)
			(layers "F.Cu" "F.Mask" "F.Paste")
			(net 1 "GND")
			(pinfunction "GND")
			(pintype "passive")
		)
		(pad "AA1" smd circle
			(at -12.5 7.499 180)
			(size 0.5 0.5)
			(layers "F.Cu" "F.Mask" "F.Paste")
			(net 206 "+1V1")
			(pinfunction "VCCO_34")
			(pintype "power_in")
		)
		(pad "AA2" smd circle
			(at -11.5 7.499 180)
			(size 0.5 0.5)
			(layers "F.Cu" "F.Mask" "F.Paste")
			(net 260 "/DDR5 SODIMM/B.DQ17")
			(pinfunction "IO_L12N_T1_MRCC_34")
			(pintype "bidirectional")
			(die_length 19.51)
		)
		(pad "AA3" smd circle
			(at -10.5 7.499 180)
			(size 0.5 0.5)
			(layers "F.Cu" "F.Mask" "F.Paste")
			(net 194 "/DDR5 SODIMM/B.CB2")
			(pinfunction "IO_L12P_T1_MRCC_34")
			(pintype "bidirectional")
			(die_length 19.161)
		)
		(pad "AA4" smd circle
			(at -9.5 7.499 180)
			(size 0.5 0.5)
			(layers "F.Cu" "F.Mask" "F.Paste")
			(net 258 "/DDR5 SODIMM/B.DQ15")
			(pinfunction "IO_L13P_T2_MRCC_34")
			(pintype "bidirectional")
			(die_length 19.112)
		)
		(pad "AA5" smd circle
			(at -8.5 7.499 180)
			(size 0.5 0.5)
			(layers "F.Cu" "F.Mask" "F.Paste")
			(net 253 "/DDR5 SODIMM/B.DQS1_P")
			(pinfunction "IO_L15P_T2_DQS_34")
			(pintype "bidirectional")
			(die_length 18.268)
		)
		(pad "AA6" smd circle
			(at -7.5 7.499 180)
			(size 0.5 0.5)
			(layers "F.Cu" "F.Mask" "F.Paste")
			(net 1 "GND")
			(pinfunction "GND")
			(pintype "passive")
		)
		(pad "AA7" smd circle
			(at -6.5 7.499 180)
			(size 0.5 0.5)
			(layers "F.Cu" "F.Mask" "F.Paste")
			(net 156 "/DDR5 SODIMM/A.CA12")
			(pinfunction "IO_L8N_T1_33")
			(pintype "bidirectional")
			(die_length 16.325)
		)
		(pad "AA8" smd circle
			(at -5.5 7.499 180)
			(size 0.5 0.5)
			(layers "F.Cu" "F.Mask" "F.Paste")
			(net 153 "/DDR5 SODIMM/A.CA9")
			(pinfunction "IO_L8P_T1_33")
			(pintype "bidirectional")
			(die_length 15.251)
		)
		(pad "AA9" smd circle
			(at -4.5 7.499 180)
			(size 0.5 0.5)
			(layers "F.Cu" "F.Mask" "F.Paste")
			(net 149 "/DDR5 SODIMM/A.CA5")
			(pinfunction "IO_L11P_T1_SRCC_33")
			(pintype "bidirectional")
			(die_length 13.773)
		)
		(pad "AA10" smd circle
			(at -3.5 7.499 180)
			(size 0.5 0.5)
			(layers "F.Cu" "F.Mask" "F.Paste")
			(net 161 "/DDR5 SODIMM/B.CK0_P")
			(pinfunction "IO_L14P_T2_SRCC_33")
			(pintype "bidirectional")
			(die_length 14.881)
		)
		(pad "AA11" smd circle
			(at -2.5 7.499 180)
			(size 0.5 0.5)
			(layers "F.Cu" "F.Mask" "F.Paste")
			(net 206 "+1V1")
			(pinfunction "VCCO_33")
			(pintype "power_in")
		)
		(pad "AA12" smd circle
			(at -1.5 7.499 180)
			(size 0.5 0.5)
			(layers "F.Cu" "F.Mask" "F.Paste")
			(net 120 "/DDR5 SODIMM/A.~{CS0}")
			(pinfunction "IO_L16N_T2_33")
			(pintype "bidirectional")
			(die_length 14.923)
		)
		(pad "AA13" smd circle
			(at -0.5 7.499 180)
			(size 0.5 0.5)
			(layers "F.Cu" "F.Mask" "F.Paste")
			(net 170 "/DDR5 SODIMM/B.CA7")
			(pinfunction "IO_L16P_T2_33")
			(pintype "bidirectional")
			(die_length 16.493)
		)
		(pad "AA14" smd circle
			(at 0.499 7.499 180)
			(size 0.5 0.5)
			(layers "F.Cu" "F.Mask" "F.Paste")
			(net 114 "/DDR5 SODIMM/A.CB0")
			(pinfunction "IO_L7P_T1_32")
			(pintype "bidirectional")
			(die_length 11.726)
		)
		(pad "AA15" smd circle
			(at 1.499 7.499 180)
			(size 0.5 0.5)
			(layers "F.Cu" "F.Mask" "F.Paste")
			(net 94 "/DDR5 SODIMM/A.~{DM2}")
			(pinfunction "IO_L7N_T1_32")
			(pintype "bidirectional")
			(die_length 11.467)
		)
		(pad "AA16" smd circle
			(at 2.499 7.499 180)
			(size 0.5 0.5)
			(layers "F.Cu" "F.Mask" "F.Paste")
			(net 1 "GND")
			(pinfunction "GND")
			(pintype "passive")
		)
		(pad "AA17" smd circle
			(at 3.499 7.499 180)
			(size 0.5 0.5)
			(layers "F.Cu" "F.Mask" "F.Paste")
			(net 91 "/DDR5 SODIMM/A.DQ17")
			(pinfunction "IO_L11P_T1_SRCC_32")
			(pintype "bidirectional")
			(die_length 14.572)
		)
		(pad "AA18" smd circle
			(at 4.499 7.499 180)
			(size 0.5 0.5)
			(layers "F.Cu" "F.Mask" "F.Paste")
			(net 89 "/DDR5 SODIMM/A.DQ16")
			(pinfunction "IO_L11N_T1_SRCC_32")
			(pintype "bidirectional")
			(die_length 14.747)
		)
		(pad "AA19" smd circle
			(at 5.499 7.499 180)
			(size 0.5 0.5)
			(layers "F.Cu" "F.Mask" "F.Paste")
			(net 74 "/DDR5 SODIMM/A.DQ8")
			(pinfunction "IO_L16P_T2_32")
			(pintype "bidirectional")
			(die_length 19.389)
		)
		(pad "AA20" smd circle
			(at 6.499 7.499 180)
			(size 0.5 0.5)
			(layers "F.Cu" "F.Mask" "F.Paste")
			(net 80 "/DDR5 SODIMM/A.DQ11")
			(pinfunction "IO_L16N_T2_32")
			(pintype "bidirectional")
			(die_length 21.053)
		)
		(pad "AA21" smd circle
			(at 7.499 7.499 180)
			(size 0.5 0.5)
			(layers "F.Cu" "F.Mask" "F.Paste")
			(net 200 "+3V3")
			(pinfunction "VCCO_12")
			(pintype "power_in")
		)
		(pad "AA22" smd circle
			(at 8.499 7.499 180)
			(size 0.5 0.5)
			(layers "F.Cu" "F.Mask" "F.Paste")
			(net 681 "/Ethernet/ETH.~{RESET}")
			(pinfunction "IO_L13N_T2_MRCC_12")
			(pintype "bidirectional")
			(die_length 11.687)
		)
		(pad "AA23" smd circle
			(at 9.499 7.499 180)
			(size 0.5 0.5)
			(layers "F.Cu" "F.Mask" "F.Paste")
			(net 679 "/Ethernet/ETH.REF_CLK")
			(pinfunction "IO_L11P_T1_SRCC_12")
			(pintype "bidirectional")
			(die_length 13.863)
		)
		(pad "AA24" smd circle
			(at 10.499 7.499 180)
			(size 0.5 0.5)
			(layers "F.Cu" "F.Mask" "F.Paste")
			(net 704 "/Ethernet/ETH.TXC")
			(pinfunction "IO_L12N_T1_MRCC_12")
			(pintype "bidirectional")
			(die_length 13.119)
		)
		(pad "AA25" smd circle
			(at 11.499 7.499 180)
			(size 0.5 0.5)
			(layers "F.Cu" "F.Mask" "F.Paste")
			(net 705 "/Ethernet/ETH.MDC")
			(pinfunction "IO_L7P_T1_12")
			(pintype "bidirectional")
			(die_length 15.139)
		)
		(pad "AA26" smd circle
			(at 12.499 7.499 180)
			(size 0.5 0.5)
			(layers "F.Cu" "F.Mask" "F.Paste")
			(net 1 "GND")
			(pinfunction "GND")
			(pintype "passive")
		)
		(pad "AB1" smd circle
			(at -12.5 8.499 180)
			(size 0.5 0.5)
			(layers "F.Cu" "F.Mask" "F.Paste")
			(net 266 "/DDR5 SODIMM/B.DQS2_P")
			(pinfunction "IO_L9P_T1_DQS_34")
			(pintype "bidirectional")
			(die_length 21.468)
		)
		(pad "AB2" smd circle
			(at -11.5 8.499 180)
			(size 0.5 0.5)
			(layers "F.Cu" "F.Mask" "F.Paste")
			(net 259 "/DDR5 SODIMM/B.DQ16")
			(pinfunction "IO_L11P_T1_SRCC_34")
			(pintype "bidirectional")
			(die_length 21.477)
		)
		(pad "AB3" smd circle
			(at -10.5 8.499 180)
			(size 0.5 0.5)
			(layers "F.Cu" "F.Mask" "F.Paste")
			(net 1 "GND")
			(pinfunction "GND")
			(pintype "passive")
		)
		(pad "AB4" smd circle
			(at -9.5 8.499 180)
			(size 0.5 0.5)
			(layers "F.Cu" "F.Mask" "F.Paste")
			(net 257 "/DDR5 SODIMM/B.DQ14")
			(pinfunction "IO_L13N_T2_MRCC_34")
			(pintype "bidirectional")
			(die_length 19.11)
		)
		(pad "AB5" smd circle
			(at -8.5 8.499 180)
			(size 0.5 0.5)
			(layers "F.Cu" "F.Mask" "F.Paste")
			(net 250 "/DDR5 SODIMM/B.DQS1_N")
			(pinfunction "IO_L15N_T2_DQS_34")
			(pintype "bidirectional")
			(die_length 17.889)
		)
		(pad "AB6" smd circle
			(at -7.5 8.499 180)
			(size 0.5 0.5)
			(layers "F.Cu" "F.Mask" "F.Paste")
			(net 228 "/DDR5 SODIMM/B.DQ8")
			(pinfunction "IO_L16P_T2_34")
			(pintype "bidirectional")
			(die_length 18.462)
		)
		(pad "AB7" smd circle
			(at -6.5 8.499 180)
			(size 0.5 0.5)
			(layers "F.Cu" "F.Mask" "F.Paste")
			(net 155 "/DDR5 SODIMM/A.CA11")
			(pinfunction "IO_L10P_T1_33")
			(pintype "bidirectional")
			(die_length 14.818)
		)
		(pad "AB8" smd circle
			(at -5.5 8.499 180)
			(size 0.5 0.5)
			(layers "F.Cu" "F.Mask" "F.Paste")
			(net 206 "+1V1")
			(pinfunction "VCCO_33")
			(pintype "passive")
		)
		(pad "AB9" smd circle
			(at -4.5 8.499 180)
			(size 0.5 0.5)
			(layers "F.Cu" "F.Mask" "F.Paste")
			(net 150 "/DDR5 SODIMM/A.CA6")
			(pinfunction "IO_L11N_T1_SRCC_33")
			(pintype "bidirectional")
			(die_length 13.992)
		)
		(pad "AB10" smd circle
			(at -3.5 8.499 180)
			(size 0.5 0.5)
			(layers "F.Cu" "F.Mask" "F.Paste")
			(net 163 "/DDR5 SODIMM/B.CK0_N")
			(pinfunction "IO_L14N_T2_SRCC_33")
			(pintype "bidirectional")
			(die_length 15.337)
		)
		(pad "AB11" smd circle
			(at -2.5 8.499 180)
			(size 0.5 0.5)
			(layers "F.Cu" "F.Mask" "F.Paste")
			(net 157 "/DDR5 SODIMM/A.CK0_P")
			(pinfunction "IO_L13P_T2_MRCC_33")
			(pintype "bidirectional")
			(die_length 18.178)
		)
		(pad "AB12" smd circle
			(at -1.5 8.499 180)
			(size 0.5 0.5)
			(layers "F.Cu" "F.Mask" "F.Paste")
			(net 138 "/DDR5 SODIMM/A.~{CS1}")
			(pinfunction "IO_L15P_T2_DQS_33")
			(pintype "bidirectional")
			(die_length 19.224)
		)
		(pad "AB13" smd circle
			(at -0.5 8.499 180)
			(size 0.5 0.5)
			(layers "F.Cu" "F.Mask" "F.Paste")
			(net 1 "GND")
			(pinfunction "GND")
			(pintype "passive")
		)
		(pad "AB14" smd circle
			(at 0.499 8.499 180)
			(size 0.5 0.5)
			(layers "F.Cu" "F.Mask" "F.Paste")
			(net 99 "/DDR5 SODIMM/A.DQ22")
			(pinfunction "IO_L10P_T1_32")
			(pintype "bidirectional")
			(die_length 14.652)
		)
		(pad "AB15" smd circle
			(at 1.499 8.499 180)
			(size 0.5 0.5)
			(layers "F.Cu" "F.Mask" "F.Paste")
			(net 100 "/DDR5 SODIMM/A.DQ23")
			(pinfunction "IO_L10N_T1_32")
			(pintype "bidirectional")
			(die_length 16.86)
		)
		(pad "AB16" smd circle
			(at 2.499 8.499 180)
			(size 0.5 0.5)
			(layers "F.Cu" "F.Mask" "F.Paste")
			(net 92 "/DDR5 SODIMM/A.DQ18")
			(pinfunction "IO_L12P_T1_MRCC_32")
			(pintype "bidirectional")
			(die_length 17.498)
		)
		(pad "AB17" smd circle
			(at 3.499 8.499 180)
			(size 0.5 0.5)
			(layers "F.Cu" "F.Mask" "F.Paste")
			(net 77 "/DDR5 SODIMM/A.DQ9")
			(pinfunction "IO_L14P_T2_SRCC_32")
			(pintype "bidirectional")
			(die_length 16.709)
		)
		(pad "AB18" smd circle
			(at 4.499 8.499 180)
			(size 0.5 0.5)
			(layers "F.Cu" "F.Mask" "F.Paste")
			(net 206 "+1V1")
			(pinfunction "VCCO_32")
			(pintype "power_in")
		)
		(pad "AB19" smd circle
			(at 5.499 8.499 180)
			(size 0.5 0.5)
			(layers "F.Cu" "F.Mask" "F.Paste")
			(net 79 "/DDR5 SODIMM/A.DQ10")
			(pinfunction "IO_L18P_T2_32")
			(pintype "bidirectional")
			(die_length 21.632)
		)
		(pad "AB20" smd circle
			(at 6.499 8.499 180)
			(size 0.5 0.5)
			(layers "F.Cu" "F.Mask" "F.Paste")
			(net 115 "/DDR5 SODIMM/A.CB1")
			(pinfunction "IO_L18N_T2_32")
			(pintype "bidirectional")
			(die_length 20.965)
		)
	)
)
